(kicad_pcb
	(version 20260206)
	(generator "pcbnew")
	(generator_version "10.0")
	(general
		(thickness 1.6)
		(legacy_teardrops no)
	)
	(paper "A4")
	(title_block
		(title "v1-chassis-manager — T6M_CM_d_v01_1031_1645.brd")
		(comment 1 "Open CloudServer (Microsoft) / footprint 1507 of 2512 (U2), pads 1-119 of 1283")
	)
	(layers
		(0 "F.Cu" signal "TOP")
		(4 "In1.Cu" signal "GND1")
		(6 "In2.Cu" signal "IN1")
		(8 "In3.Cu" signal "VCC1")
		(10 "In4.Cu" signal "VCC2")
		(12 "In5.Cu" signal "GND2")
		(14 "In6.Cu" signal "IN2")
		(16 "In7.Cu" signal "IN3")
		(18 "In8.Cu" signal "GND3")
		(2 "B.Cu" signal "BOTTOM")
		(9 "F.Adhes" user "F.Adhesive")
		(11 "B.Adhes" user "B.Adhesive")
		(13 "F.Paste" user "Package Geometry/Pastemask Top")
		(15 "B.Paste" user "Package Geometry/Pastemask Bottom")
		(5 "F.SilkS" user "Ref Des/Silkscreen Top")
		(7 "B.SilkS" user "Ref Des/Silkscreen Bottom")
		(1 "F.Mask" user "Board Geometry/Soldermask Top")
		(3 "B.Mask" user "Board Geometry/Soldermask Bottom")
		(17 "Dwgs.User" user "User.Drawings")
		(19 "Cmts.User" user "User.Comments")
		(21 "Eco1.User" user "User.Eco1")
		(23 "Eco2.User" user "User.Eco2")
		(25 "Edge.Cuts" user "Board Geometry/Outline")
		(27 "Margin" user)
		(31 "F.CrtYd" user "Package Geometry/Place Bound Top")
		(29 "B.CrtYd" user "Package Geometry/Place Bound Bottom")
		(35 "F.Fab" user "Ref Des/Assembly Top")
		(33 "B.Fab" user "Ref Des/Assembly Bottom")
	)
	(footprint ""
		(layer "F.Cu")
		(at 58.000646 -75.799442)
		(property "Reference" "U2"
			(at -20.2438 -18.364708 0)
			(unlocked yes)
			(layer "F.SilkS")
			(effects
				(font
					(size 1.6002 1.1938)
					(thickness 0.1524)
				)
				(justify left)
			)
		)
		(property "Value" ""
			(at 0 0 0)
			(layer "F.Fab")
			(effects
				(font
					(size 1.27 1.27)
				)
			)
		)
		(duplicate_pad_numbers_are_jumpers no)
		(pad "A5" smd circle
			(at -14.485366 -13.110972)
			(size 0.4064 0.4064)
			(layers "F.Cu" "F.Mask" "F.Paste")
			(net "GND")
		)
		(pad "A6" smd circle
			(at -13.672566 -13.110972)
			(size 0.4064 0.4064)
			(layers "F.Cu" "F.Mask" "F.Paste")
			(net "GND")
		)
		(pad "A8" smd oval
			(at -12.859766 -13.110972)
			(size 0.2794 0.3429)
			(layers "F.Cu" "F.Mask" "F.Paste")
			(net "GND")
		)
		(pad "A9" smd oval
			(at -12.173458 -13.249402)
			(size 0.254 0.3429)
			(layers "F.Cu" "F.Mask" "F.Paste")
			(net "GND")
		)
		(pad "A12" smd oval
			(at -10.547858 -13.249402)
			(size 0.254 0.3429)
			(layers "F.Cu" "F.Mask" "F.Paste")
			(net "GND")
		)
		(pad "A15" smd oval
			(at -9.109202 -13.249402)
			(size 0.254 0.3429)
			(layers "F.Cu" "F.Mask" "F.Paste")
			(net "GND")
		)
		(pad "A18" smd oval
			(at -7.670546 -13.249402)
			(size 0.254 0.3429)
			(layers "F.Cu" "F.Mask" "F.Paste")
			(net "GND")
		)
		(pad "A21" smd oval
			(at -6.044946 -13.249402)
			(size 0.254 0.3429)
			(layers "F.Cu" "F.Mask" "F.Paste")
			(net "GND")
		)
		(pad "A24" smd oval
			(at -4.60629 -13.249402)
			(size 0.254 0.3429)
			(layers "F.Cu" "F.Mask" "F.Paste")
			(net "GND")
		)
		(pad "A27" smd oval
			(at -3.167634 -13.249402)
			(size 0.254 0.3429)
			(layers "F.Cu" "F.Mask" "F.Paste")
			(net "GND")
		)
		(pad "A30" smd oval
			(at -1.542034 -13.249402)
			(size 0.254 0.3429)
			(layers "F.Cu" "F.Mask" "F.Paste")
			(net "GND")
		)
		(pad "A33" smd oval
			(at -0.103378 -13.249402)
			(size 0.254 0.3429)
			(layers "F.Cu" "F.Mask" "F.Paste")
			(net "GND")
		)
		(pad "A36" smd oval
			(at 1.335278 -13.249402)
			(size 0.254 0.3429)
			(layers "F.Cu" "F.Mask" "F.Paste")
			(net "GND")
		)
		(pad "A39" smd oval
			(at 2.960878 -13.249402)
			(size 0.254 0.3429)
			(layers "F.Cu" "F.Mask" "F.Paste")
			(net "GND")
		)
		(pad "A42" smd oval
			(at 4.399534 -13.249402)
			(size 0.254 0.3429)
			(layers "F.Cu" "F.Mask" "F.Paste")
			(net "GND")
		)
		(pad "A45" smd oval
			(at 5.83819 -13.249402)
			(size 0.254 0.3429)
			(layers "F.Cu" "F.Mask" "F.Paste")
			(net "GND")
		)
		(pad "A48" smd oval
			(at 7.46379 -13.249402)
			(size 0.254 0.3429)
			(layers "F.Cu" "F.Mask" "F.Paste")
			(net "SPC_CPU_NODE1_DTR_L")
		)
		(pad "A51" smd oval
			(at 8.902446 -13.249402)
			(size 0.254 0.3429)
			(layers "F.Cu" "F.Mask" "F.Paste")
			(net "TP_CPU_NODE1_C2F_LP_MODE")
		)
		(pad "A54" smd oval
			(at 10.341102 -13.249402)
			(size 0.254 0.3429)
			(layers "F.Cu" "F.Mask" "F.Paste")
			(net "GND")
		)
		(pad "A57" smd oval
			(at 11.966702 -13.249402)
			(size 0.254 0.3429)
			(layers "F.Cu" "F.Mask" "F.Paste")
			(net "GND")
		)
		(pad "A59" smd oval
			(at 12.859766 -13.110972)
			(size 0.2794 0.3429)
			(layers "F.Cu" "F.Mask" "F.Paste")
			(net "GND")
		)
		(pad "A61" smd circle
			(at 13.672566 -13.110972)
			(size 0.4064 0.4064)
			(layers "F.Cu" "F.Mask" "F.Paste")
			(net "GND")
		)
		(pad "A62" smd circle
			(at 14.485366 -13.110972)
			(size 0.4064 0.4064)
			(layers "F.Cu" "F.Mask" "F.Paste")
			(net "GND")
		)
		(pad "A64" smd circle
			(at 15.298166 -13.110972)
			(size 0.4064 0.4064)
			(layers "F.Cu" "F.Mask" "F.Paste")
			(net "GND")
		)
		(pad "A66" smd circle
			(at 16.110966 -13.110972)
			(size 0.4064 0.4064)
			(layers "F.Cu" "F.Mask" "F.Paste")
			(net "GND")
		)
		(pad "AA3" smd circle
			(at -15.247112 -3.216402)
			(size 0.3048 0.3048)
			(layers "F.Cu" "F.Mask" "F.Paste")
			(net "GND")
		)
		(pad "AA5" smd circle
			(at -14.013688 -3.186176)
			(size 0.3048 0.3048)
			(layers "F.Cu" "F.Mask" "F.Paste")
			(net "GND")
		)
		(pad "AA21" smd circle
			(at -6.00075 -3.2004)
			(size 0.381 0.381)
			(layers "F.Cu" "F.Mask" "F.Paste")
			(net "P1V5_NODE1_AA21")
		)
		(pad "AA23" smd circle
			(at -5.20065 -3.2004)
			(size 0.381 0.381)
			(layers "F.Cu" "F.Mask" "F.Paste")
			(net "PD_NODE1_NTB_RCOMP")
		)
		(pad "AA25" smd circle
			(at -4.40055 -3.2004)
			(size 0.381 0.381)
			(layers "F.Cu" "F.Mask" "F.Paste")
			(net "GND")
		)
		(pad "AA26" smd circle
			(at -3.60045 -3.2004)
			(size 0.381 0.381)
			(layers "F.Cu" "F.Mask" "F.Paste")
			(net "GND")
		)
		(pad "AA28" smd circle
			(at -2.80035 -3.2004)
			(size 0.381 0.381)
			(layers "F.Cu" "F.Mask" "F.Paste")
			(net "P1V5_NODE1")
		)
		(pad "AA29" smd circle
			(at -2.00025 -3.2004)
			(size 0.381 0.381)
			(layers "F.Cu" "F.Mask" "F.Paste")
			(net "GND")
		)
		(pad "AA31" smd circle
			(at -1.20015 -3.2004)
			(size 0.381 0.381)
			(layers "F.Cu" "F.Mask" "F.Paste")
			(net "P1V05_NODE1")
		)
		(pad "AA32" smd circle
			(at -0.40005 -3.2004)
			(size 0.381 0.381)
			(layers "F.Cu" "F.Mask" "F.Paste")
			(net "GND")
		)
		(pad "AA34" smd circle
			(at 0.40005 -3.2004)
			(size 0.381 0.381)
			(layers "F.Cu" "F.Mask" "F.Paste")
			(net "P1V05_NODE1")
		)
		(pad "AA36" smd circle
			(at 1.20015 -3.2004)
			(size 0.381 0.381)
			(layers "F.Cu" "F.Mask" "F.Paste")
			(net "GND")
		)
		(pad "AA38" smd circle
			(at 2.00025 -3.2004)
			(size 0.381 0.381)
			(layers "F.Cu" "F.Mask" "F.Paste")
			(net "P1V05_NODE1")
		)
		(pad "AA39" smd circle
			(at 2.80035 -3.2004)
			(size 0.381 0.381)
			(layers "F.Cu" "F.Mask" "F.Paste")
			(net "GND")
		)
		(pad "AA41" smd circle
			(at 3.60045 -3.2004)
			(size 0.381 0.381)
			(layers "F.Cu" "F.Mask" "F.Paste")
			(net "P1V05_NODE1")
		)
		(pad "AA42" smd circle
			(at 4.40055 -3.2004)
			(size 0.381 0.381)
			(layers "F.Cu" "F.Mask" "F.Paste")
			(net "GND")
		)
		(pad "AA44" smd circle
			(at 5.20065 -3.2004)
			(size 0.381 0.381)
			(layers "F.Cu" "F.Mask" "F.Paste")
			(net "PV_VCCP_NODE1")
		)
		(pad "AA46" smd circle
			(at 6.00075 -3.2004)
			(size 0.381 0.381)
			(layers "F.Cu" "F.Mask" "F.Paste")
			(net "PV_VCCP_NODE1")
		)
		(pad "AA47" smd circle
			(at 6.841998 -3.156204)
			(size 0.3048 0.3048)
			(layers "F.Cu" "F.Mask" "F.Paste")
			(net "GND")
		)
		(pad "AA62" smd circle
			(at 14.08049 -3.38836)
			(size 0.3048 0.3048)
			(layers "F.Cu" "F.Mask" "F.Paste")
			(net "XDP_SOC_CPU_NODE1_TRST_L")
		)
		(pad "AA64" smd circle
			(at 15.242794 -3.398266)
			(size 0.3048 0.3048)
			(layers "F.Cu" "F.Mask" "F.Paste")
			(net "XDP_SOC_CPU_NODE1_TDO")
		)
		(pad "AA66" smd oval
			(at 16.249396 -3.167888 90)
			(size 0.254 0.3429)
			(layers "F.Cu" "F.Mask" "F.Paste")
			(net "XDP_SOC_CPU_NODE1_TDI")
		)
		(pad "AB1" smd oval
			(at -16.249396 -2.960624 270)
			(size 0.254 0.3429)
			(layers "F.Cu" "F.Mask" "F.Paste")
			(net "GND")
		)
		(pad "AB2" smd circle
			(at -15.640812 -2.61112)
			(size 0.3048 0.3048)
			(layers "F.Cu" "F.Mask" "F.Paste")
			(net "PD_CPU_NODE1_RP2_PERP")
		)
		(pad "AB4" smd circle
			(at -14.90091 -2.605024)
			(size 0.3048 0.3048)
			(layers "F.Cu" "F.Mask" "F.Paste")
			(net "PD_CPU_NODE1_RP2_PERN")
		)
		(pad "AB5" smd circle
			(at -14.204442 -2.507996)
			(size 0.3048 0.3048)
			(layers "F.Cu" "F.Mask" "F.Paste")
			(net "PD_CPU_NODE1_RP2_PERP")
		)
		(pad "AB20" smd circle
			(at -6.841998 -2.916428)
			(size 0.3048 0.3048)
			(layers "F.Cu" "F.Mask" "F.Paste")
			(net "GND")
		)
		(pad "AB62" smd circle
			(at 14.204442 -2.69494)
			(size 0.3048 0.3048)
			(layers "F.Cu" "F.Mask" "F.Paste")
			(net "SVID_CPU_NODE1_PVCCP_CLK")
		)
		(pad "AB63" smd circle
			(at 14.90091 -2.786888)
			(size 0.3048 0.3048)
			(layers "F.Cu" "F.Mask" "F.Paste")
			(net "SVID_CPU_NODE1_PVCCP_ALERT_R_L")
		)
		(pad "AB65" smd circle
			(at 15.639034 -2.818384)
			(size 0.3048 0.3048)
			(layers "F.Cu" "F.Mask" "F.Paste")
			(net "GND")
		)
		(pad "AC8" smd circle
			(at -12.963398 -2.216404)
			(size 0.3048 0.3048)
			(layers "F.Cu" "F.Mask" "F.Paste")
			(net "GND")
		)
		(pad "AC9" smd circle
			(at -12.201398 -2.216404)
			(size 0.3048 0.3048)
			(layers "F.Cu" "F.Mask" "F.Paste")
			(net "Net_380")
		)
		(pad "AC11" smd circle
			(at -11.439398 -2.216404)
			(size 0.3048 0.3048)
			(layers "F.Cu" "F.Mask" "F.Paste")
			(net "Net_393")
		)
		(pad "AC12" smd circle
			(at -10.677398 -2.216404)
			(size 0.3048 0.3048)
			(layers "F.Cu" "F.Mask" "F.Paste")
			(net "GND")
		)
		(pad "AC14" smd circle
			(at -9.915398 -2.216404)
			(size 0.3048 0.3048)
			(layers "F.Cu" "F.Mask" "F.Paste")
			(net "Net_396")
		)
		(pad "AC15" smd circle
			(at -9.153398 -2.216404)
			(size 0.3048 0.3048)
			(layers "F.Cu" "F.Mask" "F.Paste")
			(net "Net_371")
		)
		(pad "AC17" smd circle
			(at -8.391398 -2.216404)
			(size 0.3048 0.3048)
			(layers "F.Cu" "F.Mask" "F.Paste")
			(net "GND")
		)
		(pad "AC18" smd circle
			(at -7.629398 -2.216404)
			(size 0.3048 0.3048)
			(layers "F.Cu" "F.Mask" "F.Paste")
			(net "P1V05_NODE1")
		)
		(pad "AC20" smd circle
			(at -6.929374 -2.216404)
			(size 0.3048 0.3048)
			(layers "F.Cu" "F.Mask" "F.Paste")
			(net "P1V05_NODE1")
		)
		(pad "AC21" smd circle
			(at -6.00075 -2.4003)
			(size 0.381 0.381)
			(layers "F.Cu" "F.Mask" "F.Paste")
			(net "P1V05_NODE1")
		)
		(pad "AC23" smd circle
			(at -5.20065 -2.4003)
			(size 0.381 0.381)
			(layers "F.Cu" "F.Mask" "F.Paste")
			(net "P1V05_NODE1")
		)
		(pad "AC25" smd circle
			(at -4.40055 -2.4003)
			(size 0.381 0.381)
			(layers "F.Cu" "F.Mask" "F.Paste")
			(net "P1V05_NODE1")
		)
		(pad "AC26" smd circle
			(at -3.60045 -2.4003)
			(size 0.381 0.381)
			(layers "F.Cu" "F.Mask" "F.Paste")
			(net "P1V05_NODE1")
		)
		(pad "AC28" smd circle
			(at -2.80035 -2.4003)
			(size 0.381 0.381)
			(layers "F.Cu" "F.Mask" "F.Paste")
			(net "GND")
		)
		(pad "AC29" smd circle
			(at -2.00025 -2.4003)
			(size 0.381 0.381)
			(layers "F.Cu" "F.Mask" "F.Paste")
			(net "GND")
		)
		(pad "AC31" smd circle
			(at -1.20015 -2.4003)
			(size 0.381 0.381)
			(layers "F.Cu" "F.Mask" "F.Paste")
			(net "P1V05_NODE1")
		)
		(pad "AC32" smd circle
			(at -0.40005 -2.4003)
			(size 0.381 0.381)
			(layers "F.Cu" "F.Mask" "F.Paste")
			(net "GND")
		)
		(pad "AC34" smd circle
			(at 0.40005 -2.4003)
			(size 0.381 0.381)
			(layers "F.Cu" "F.Mask" "F.Paste")
			(net "P1V05_NODE1")
		)
		(pad "AC36" smd circle
			(at 1.20015 -2.4003)
			(size 0.381 0.381)
			(layers "F.Cu" "F.Mask" "F.Paste")
			(net "P1V05_NODE1")
		)
		(pad "AC38" smd circle
			(at 2.00025 -2.4003)
			(size 0.381 0.381)
			(layers "F.Cu" "F.Mask" "F.Paste")
			(net "A_CPU0_NODE1_THERMDC")
		)
		(pad "AC39" smd circle
			(at 2.80035 -2.4003)
			(size 0.381 0.381)
			(layers "F.Cu" "F.Mask" "F.Paste")
			(net "GND")
		)
		(pad "AC41" smd circle
			(at 3.60045 -2.4003)
			(size 0.381 0.381)
			(layers "F.Cu" "F.Mask" "F.Paste")
			(net "TP_CPU_NODE1_VCCCPU0VIDSI0GT1P0")
		)
		(pad "AC42" smd circle
			(at 4.40055 -2.4003)
			(size 0.381 0.381)
			(layers "F.Cu" "F.Mask" "F.Paste")
			(net "TP_CPU_NODE1_VCCCPU0VIDSI0GT1_1")
		)
		(pad "AC44" smd circle
			(at 5.20065 -2.4003)
			(size 0.381 0.381)
			(layers "F.Cu" "F.Mask" "F.Paste")
			(net "PV_VCCP_NODE1")
		)
		(pad "AC46" smd circle
			(at 6.00075 -2.4003)
			(size 0.381 0.381)
			(layers "F.Cu" "F.Mask" "F.Paste")
			(net "GND")
		)
		(pad "AC47" smd circle
			(at 6.929374 -2.45618)
			(size 0.3048 0.3048)
			(layers "F.Cu" "F.Mask" "F.Paste")
			(net "A_CPU_NODE1_LV_GPIO_RCOMP")
		)
		(pad "AC49" smd circle
			(at 7.629398 -2.45618)
			(size 0.3048 0.3048)
			(layers "F.Cu" "F.Mask" "F.Paste")
			(net "P1V05_VCCPLLCPU0SIO_NODE1")
		)
		(pad "AC50" smd circle
			(at 8.391398 -2.45618)
			(size 0.3048 0.3048)
			(layers "F.Cu" "F.Mask" "F.Paste")
			(net "GND")
		)
		(pad "AC52" smd circle
			(at 9.153398 -2.45618)
			(size 0.3048 0.3048)
			(layers "F.Cu" "F.Mask" "F.Paste")
			(net "XDP_CPU_NODE1_PRDY_L")
		)
		(pad "AC53" smd circle
			(at 9.915398 -2.45618)
			(size 0.3048 0.3048)
			(layers "F.Cu" "F.Mask" "F.Paste")
			(net "FM_CPU_NODE1_JTAG_POK")
		)
		(pad "AC55" smd circle
			(at 10.677398 -2.45618)
			(size 0.3048 0.3048)
			(layers "F.Cu" "F.Mask" "F.Paste")
			(net "GND")
		)
		(pad "AC56" smd circle
			(at 11.439398 -2.45618)
			(size 0.3048 0.3048)
			(layers "F.Cu" "F.Mask" "F.Paste")
			(net "H_CPU_NODE1_PROCHOT_R")
		)
		(pad "AC58" smd circle
			(at 12.201398 -2.45618)
			(size 0.3048 0.3048)
			(layers "F.Cu" "F.Mask" "F.Paste")
			(net "SVID_CPU_NODE1_PVCCP_DAT_R")
		)
		(pad "AC59" smd circle
			(at 12.963398 -2.45618)
			(size 0.3048 0.3048)
			(layers "F.Cu" "F.Mask" "F.Paste")
			(net "GND")
		)
		(pad "AD2" smd circle
			(at -15.639034 -1.684528)
			(size 0.3048 0.3048)
			(layers "F.Cu" "F.Mask" "F.Paste")
			(net "PD_CPU_NODE1_RP2_PERP")
		)
		(pad "AD4" smd circle
			(at -14.90091 -1.716024)
			(size 0.3048 0.3048)
			(layers "F.Cu" "F.Mask" "F.Paste")
			(net "PD_CPU_NODE1_RP2_PERN")
		)
		(pad "AD5" smd circle
			(at -14.204442 -1.807972)
			(size 0.3048 0.3048)
			(layers "F.Cu" "F.Mask" "F.Paste")
			(net "PD_CPU_NODE1_RP2_PERN")
		)
		(pad "AD8" smd circle
			(at -12.963398 -1.51638)
			(size 0.3048 0.3048)
			(layers "F.Cu" "F.Mask" "F.Paste")
			(net "GND")
		)
		(pad "AD9" smd circle
			(at -12.201398 -1.51638)
			(size 0.3048 0.3048)
			(layers "F.Cu" "F.Mask" "F.Paste")
			(net "Net_388")
		)
		(pad "AD11" smd circle
			(at -11.439398 -1.51638)
			(size 0.3048 0.3048)
			(layers "F.Cu" "F.Mask" "F.Paste")
			(net "Net_375")
		)
		(pad "AD12" smd circle
			(at -10.677398 -1.51638)
			(size 0.3048 0.3048)
			(layers "F.Cu" "F.Mask" "F.Paste")
			(net "GND")
		)
		(pad "AD14" smd circle
			(at -9.915398 -1.51638)
			(size 0.3048 0.3048)
			(layers "F.Cu" "F.Mask" "F.Paste")
			(net "Net_394")
		)
		(pad "AD15" smd circle
			(at -9.153398 -1.51638)
			(size 0.3048 0.3048)
			(layers "F.Cu" "F.Mask" "F.Paste")
			(net "Net_392")
		)
		(pad "AD17" smd circle
			(at -8.391398 -1.51638)
			(size 0.3048 0.3048)
			(layers "F.Cu" "F.Mask" "F.Paste")
			(net "GND")
		)
		(pad "AD18" smd circle
			(at -7.629398 -1.51638)
			(size 0.3048 0.3048)
			(layers "F.Cu" "F.Mask" "F.Paste")
			(net "P1V05_NODE1")
		)
		(pad "AD20" smd circle
			(at -6.929374 -1.51638)
			(size 0.3048 0.3048)
			(layers "F.Cu" "F.Mask" "F.Paste")
			(net "P1V05_NODE1")
		)
		(pad "AD21" smd circle
			(at -6.00075 -1.6002)
			(size 0.381 0.381)
			(layers "F.Cu" "F.Mask" "F.Paste")
			(net "GND")
		)
		(pad "AD23" smd circle
			(at -5.20065 -1.6002)
			(size 0.381 0.381)
			(layers "F.Cu" "F.Mask" "F.Paste")
			(net "P1V8_VCCASFRHPLL_NODE1")
		)
		(pad "AD25" smd circle
			(at -4.40055 -1.6002)
			(size 0.381 0.381)
			(layers "F.Cu" "F.Mask" "F.Paste")
			(net "P1V8_VCCASFRHPLL_NODE1")
		)
		(pad "AD26" smd circle
			(at -3.60045 -1.6002)
			(size 0.381 0.381)
			(layers "F.Cu" "F.Mask" "F.Paste")
			(net "GND")
		)
		(pad "AD28" smd circle
			(at -2.80035 -1.6002)
			(size 0.381 0.381)
			(layers "F.Cu" "F.Mask" "F.Paste")
			(net "P1V05_NODE1")
		)
		(pad "AD29" smd circle
			(at -2.00025 -1.6002)
			(size 0.381 0.381)
			(layers "F.Cu" "F.Mask" "F.Paste")
			(net "P1V05_NODE1")
		)
		(pad "AD31" smd circle
			(at -1.20015 -1.6002)
			(size 0.381 0.381)
			(layers "F.Cu" "F.Mask" "F.Paste")
			(net "GND")
		)
		(pad "AD32" smd circle
			(at -0.40005 -1.6002)
			(size 0.381 0.381)
			(layers "F.Cu" "F.Mask" "F.Paste")
			(net "P1V05_NODE1")
		)
		(pad "AD34" smd circle
			(at 0.40005 -1.6002)
			(size 0.381 0.381)
			(layers "F.Cu" "F.Mask" "F.Paste")
			(net "GND")
		)
		(pad "AD36" smd circle
			(at 1.20015 -1.6002)
			(size 0.381 0.381)
			(layers "F.Cu" "F.Mask" "F.Paste")
			(net "GND")
		)
		(pad "AD38" smd circle
			(at 2.00025 -1.6002)
			(size 0.381 0.381)
			(layers "F.Cu" "F.Mask" "F.Paste")
			(net "GND")
		)
		(pad "AD39" smd circle
			(at 2.80035 -1.6002)
			(size 0.381 0.381)
			(layers "F.Cu" "F.Mask" "F.Paste")
			(net "A_CPU0_NODE1_THERMDA")
		)
		(pad "AD41" smd circle
			(at 3.60045 -1.6002)
			(size 0.381 0.381)
			(layers "F.Cu" "F.Mask" "F.Paste")
			(net "VSENSE_VCC_CPU_NODE1")
		)
		(pad "AD42" smd circle
			(at 4.40055 -1.6002)
			(size 0.381 0.381)
			(layers "F.Cu" "F.Mask" "F.Paste")
			(net "GND")
		)
		(pad "AD44" smd circle
			(at 5.20065 -1.6002)
			(size 0.381 0.381)
			(layers "F.Cu" "F.Mask" "F.Paste")
			(net "GND")
		)
		(pad "AD46" smd circle
			(at 6.00075 -1.6002)
			(size 0.381 0.381)
			(layers "F.Cu" "F.Mask" "F.Paste")
			(net "GND")
		)
		(pad "AD47" smd circle
			(at 6.929374 -1.756156)
			(size 0.3048 0.3048)
			(layers "F.Cu" "F.Mask" "F.Paste")
			(net "P1V05_VCCPLLCPU1SIO_NODE1")
		)
		(pad "AD49" smd circle
			(at 7.629398 -1.756156)
			(size 0.3048 0.3048)
			(layers "F.Cu" "F.Mask" "F.Paste")
			(net "PD_CPU_NODE1_SPD_EN_L")
		)
	)
)
